(kicad_pcb
	(version 20260206)
	(generator "pcbnew")
	(generator_version "10.0")
	(general
		(thickness 1.6)
		(legacy_teardrops no)
	)
	(paper "A4")
	(title_block
		(title "v1-chassis-manager — T6M_CM_d_v01_1031_1645.brd")
		(comment 1 "Open CloudServer (Microsoft) / footprints 306-315 of 2512")
	)
	(layers
		(0 "F.Cu" signal "TOP")
		(4 "In1.Cu" signal "GND1")
		(6 "In2.Cu" signal "IN1")
		(8 "In3.Cu" signal "VCC1")
		(10 "In4.Cu" signal "VCC2")
		(12 "In5.Cu" signal "GND2")
		(14 "In6.Cu" signal "IN2")
		(16 "In7.Cu" signal "IN3")
		(18 "In8.Cu" signal "GND3")
		(2 "B.Cu" signal "BOTTOM")
		(9 "F.Adhes" user "F.Adhesive")
		(11 "B.Adhes" user "B.Adhesive")
		(13 "F.Paste" user "Package Geometry/Pastemask Top")
		(15 "B.Paste" user "Package Geometry/Pastemask Bottom")
		(5 "F.SilkS" user "Ref Des/Silkscreen Top")
		(7 "B.SilkS" user "Ref Des/Silkscreen Bottom")
		(1 "F.Mask" user "Board Geometry/Soldermask Top")
		(3 "B.Mask" user "Board Geometry/Soldermask Bottom")
		(17 "Dwgs.User" user "User.Drawings")
		(19 "Cmts.User" user "User.Comments")
		(21 "Eco1.User" user "User.Eco1")
		(23 "Eco2.User" user "User.Eco2")
		(25 "Edge.Cuts" user "Board Geometry/Outline")
		(27 "Margin" user)
		(31 "F.CrtYd" user "Package Geometry/Place Bound Top")
		(29 "B.CrtYd" user "Package Geometry/Place Bound Bottom")
		(35 "F.Fab" user "Ref Des/Assembly Top")
		(33 "B.Fab" user "Ref Des/Assembly Bottom")
	)
	(footprint ""
		(layer "F.Cu")
		(at 109.075474 -129.941574 180)
		(property "Reference" "PR51"
			(at 8.906764 -3.15849 0)
			(unlocked yes)
			(layer "F.SilkS")
			(effects
				(font
					(size 0.7874 0.5842)
					(thickness 0.1524)
				)
				(justify left)
			)
		)
		(property "Value" ""
			(at 0 0 180)
			(layer "F.Fab")
			(effects
				(font
					(size 1.27 1.27)
				)
			)
		)
		(duplicate_pad_numbers_are_jumpers no)
		(fp_line
			(start 0.7874 0.4064)
			(end -0.7874 0.4064)
			(stroke
				(width 0.1524)
				(type default)
			)
			(layer "F.SilkS")
		)
		(fp_line
			(start 0.7874 -0.4064)
			(end 0.7874 0.4064)
			(stroke
				(width 0.1524)
				(type default)
			)
			(layer "F.SilkS")
		)
		(fp_line
			(start -0.7874 0.4064)
			(end -0.7874 -0.4064)
			(stroke
				(width 0.1524)
				(type default)
			)
			(layer "F.SilkS")
		)
		(fp_line
			(start -0.7874 -0.4064)
			(end 0.7874 -0.4064)
			(stroke
				(width 0.1524)
				(type default)
			)
			(layer "F.SilkS")
		)
		(fp_poly
			(pts
				(xy -0.508 0.2794) (xy -0.508 0.2286) (xy -0.635 0.2286) (xy -0.635 -0.254) (xy -0.5334 -0.254)
				(xy -0.5334 -0.2794) (xy 0.5334 -0.2794) (xy 0.5334 -0.254) (xy 0.635 -0.254) (xy 0.635 0.254) (xy 0.5334 0.254)
				(xy 0.5334 0.2794)
			)
			(stroke
				(width 0)
				(type default)
			)
			(fill no)
			(layer "F.CrtYd")
		)
		(pad "1" smd rect
			(at 0.40005 0 180)
			(size 0.4572 0.508)
			(layers "F.Cu" "F.Mask" "F.Paste")
			(net "VR_PVCCP_NODE1_PHASE1")
		)
		(pad "2" smd rect
			(at -0.40005 0 180)
			(size 0.4572 0.508)
			(layers "F.Cu" "F.Mask" "F.Paste")
			(net "VR_PVCCP_NODE1_UGATE1")
		)
	)
	(footprint ""
		(layer "F.Cu")
		(at 114.046254 -60.239148 180)
		(property "Reference" "R225"
			(at -1.192022 -1.86944 0)
			(unlocked yes)
			(layer "F.SilkS")
			(effects
				(font
					(size 0.7874 0.5842)
					(thickness 0.1524)
				)
				(justify left)
			)
		)
		(property "Value" ""
			(at 0 0 180)
			(layer "F.Fab")
			(effects
				(font
					(size 1.27 1.27)
				)
			)
		)
		(duplicate_pad_numbers_are_jumpers no)
		(fp_line
			(start 0.7874 0.4064)
			(end -0.7874 0.4064)
			(stroke
				(width 0.1524)
				(type default)
			)
			(layer "F.SilkS")
		)
		(fp_line
			(start 0.7874 -0.4064)
			(end 0.7874 0.4064)
			(stroke
				(width 0.1524)
				(type default)
			)
			(layer "F.SilkS")
		)
		(fp_line
			(start -0.7874 0.4064)
			(end -0.7874 -0.4064)
			(stroke
				(width 0.1524)
				(type default)
			)
			(layer "F.SilkS")
		)
		(fp_line
			(start -0.7874 -0.4064)
			(end 0.7874 -0.4064)
			(stroke
				(width 0.1524)
				(type default)
			)
			(layer "F.SilkS")
		)
		(fp_poly
			(pts
				(xy -0.508 0.2794) (xy -0.508 0.2286) (xy -0.635 0.2286) (xy -0.635 -0.254) (xy -0.5334 -0.254)
				(xy -0.5334 -0.2794) (xy 0.5334 -0.2794) (xy 0.5334 -0.254) (xy 0.635 -0.254) (xy 0.635 0.254) (xy 0.5334 0.254)
				(xy 0.5334 0.2794)
			)
			(stroke
				(width 0)
				(type default)
			)
			(fill no)
			(layer "F.CrtYd")
		)
		(pad "1" smd rect
			(at 0.40005 0 180)
			(size 0.4572 0.508)
			(layers "F.Cu" "F.Mask" "F.Paste")
			(net "XDP_NODE1_P60")
		)
		(pad "2" smd rect
			(at -0.40005 0 180)
			(size 0.4572 0.508)
			(layers "F.Cu" "F.Mask" "F.Paste")
			(net "GND")
		)
	)
	(footprint ""
		(layer "F.Cu")
		(at 52.223162 -145.514822 180)
		(property "Reference" "R545"
			(at 2.169922 -6.390894 0)
			(unlocked yes)
			(layer "F.SilkS")
			(effects
				(font
					(size 0.7874 0.5842)
					(thickness 0.1524)
				)
				(justify left)
			)
		)
		(property "Value" ""
			(at 0 0 180)
			(layer "F.Fab")
			(effects
				(font
					(size 1.27 1.27)
				)
			)
		)
		(duplicate_pad_numbers_are_jumpers no)
		(fp_line
			(start 0.7874 0.4064)
			(end -0.7874 0.4064)
			(stroke
				(width 0.1524)
				(type default)
			)
			(layer "F.SilkS")
		)
		(fp_line
			(start 0.7874 -0.4064)
			(end 0.7874 0.4064)
			(stroke
				(width 0.1524)
				(type default)
			)
			(layer "F.SilkS")
		)
		(fp_line
			(start -0.7874 0.4064)
			(end -0.7874 -0.4064)
			(stroke
				(width 0.1524)
				(type default)
			)
			(layer "F.SilkS")
		)
		(fp_line
			(start -0.7874 -0.4064)
			(end 0.7874 -0.4064)
			(stroke
				(width 0.1524)
				(type default)
			)
			(layer "F.SilkS")
		)
		(fp_poly
			(pts
				(xy -0.508 0.2794) (xy -0.508 0.2286) (xy -0.635 0.2286) (xy -0.635 -0.254) (xy -0.5334 -0.254)
				(xy -0.5334 -0.2794) (xy 0.5334 -0.2794) (xy 0.5334 -0.254) (xy 0.635 -0.254) (xy 0.635 0.254) (xy 0.5334 0.254)
				(xy 0.5334 0.2794)
			)
			(stroke
				(width 0)
				(type default)
			)
			(fill no)
			(layer "F.CrtYd")
		)
		(pad "1" smd rect
			(at 0.40005 0 180)
			(size 0.4572 0.508)
			(layers "F.Cu" "F.Mask" "F.Paste")
			(net "SPI_LAN1_NVM_SK")
		)
		(pad "2" smd rect
			(at -0.40005 0 180)
			(size 0.4572 0.508)
			(layers "F.Cu" "F.Mask" "F.Paste")
			(net "LAN1_NVM_SK_R")
		)
	)
	(footprint ""
		(layer "F.Cu")
		(at 83.209384 -92.366338 180)
		(property "Reference" "C110"
			(at -3.768344 -1.0541 0)
			(unlocked yes)
			(layer "F.SilkS")
			(effects
				(font
					(size 0.7874 0.5842)
					(thickness 0.1524)
				)
			)
		)
		(property "Value" ""
			(at 0 0 180)
			(layer "F.Fab")
			(effects
				(font
					(size 1.27 1.27)
				)
			)
		)
		(duplicate_pad_numbers_are_jumpers no)
		(fp_line
			(start 1.2954 0.5842)
			(end -1.2954 0.5842)
			(stroke
				(width 0.1524)
				(type default)
			)
			(layer "F.SilkS")
		)
		(fp_line
			(start 1.2954 -0.5842)
			(end 1.2954 0.5842)
			(stroke
				(width 0.1524)
				(type default)
			)
			(layer "F.SilkS")
		)
		(fp_line
			(start 0 -0.5842)
			(end 0 0.5842)
			(stroke
				(width 0.1524)
				(type default)
			)
			(layer "F.SilkS")
		)
		(fp_line
			(start -1.2954 0.5842)
			(end -1.2954 -0.5842)
			(stroke
				(width 0.1524)
				(type default)
			)
			(layer "F.SilkS")
		)
		(fp_line
			(start -1.2954 -0.5842)
			(end 1.2954 -0.5842)
			(stroke
				(width 0.1524)
				(type default)
			)
			(layer "F.SilkS")
		)
		(fp_poly
			(pts
				(xy 0.8636 -0.4572) (xy 0.8636 -0.3556) (xy 1.143 -0.3556) (xy 1.143 0.3556) (xy 0.8636 0.3556)
				(xy 0.8636 0.4572) (xy -0.8636 0.4572) (xy -0.8636 0.3556) (xy -1.143 0.3556) (xy -1.143 -0.3556)
				(xy -0.8636 -0.3556) (xy -0.8636 -0.4572)
			)
			(stroke
				(width 0)
				(type default)
			)
			(fill no)
			(layer "F.CrtYd")
		)
		(fp_line
			(start 0.884936 0.504952)
			(end -0.884936 0.504952)
			(stroke
				(width 0.1)
				(type default)
			)
			(layer "F.Fab")
		)
		(fp_line
			(start 0.884936 -0.504952)
			(end 0.884936 0.504952)
			(stroke
				(width 0.1)
				(type default)
			)
			(layer "F.Fab")
		)
		(fp_line
			(start -0.884936 0.504952)
			(end -0.884936 -0.504952)
			(stroke
				(width 0.1)
				(type default)
			)
			(layer "F.Fab")
		)
		(fp_line
			(start -0.884936 -0.504952)
			(end 0.884936 -0.504952)
			(stroke
				(width 0.1)
				(type default)
			)
			(layer "F.Fab")
		)
		(pad "1" smd rect
			(at 0.7366 0 270)
			(size 0.7112 0.8128)
			(layers "F.Cu" "F.Mask" "F.Paste")
			(net "P3V3_SUS_NODE1")
		)
		(pad "2" smd rect
			(at -0.7366 0 270)
			(size 0.7112 0.8128)
			(layers "F.Cu" "F.Mask" "F.Paste")
			(net "GND")
		)
	)
	(footprint ""
		(layer "F.Cu")
		(at 82.190082 -162.055556 90)
		(property "Reference" "R935"
			(at -2.612136 1.126744 90)
			(unlocked yes)
			(layer "F.SilkS")
			(effects
				(font
					(size 0.7874 0.5842)
					(thickness 0.1524)
				)
				(justify left)
			)
		)
		(property "Value" ""
			(at 0 0 90)
			(layer "F.Fab")
			(effects
				(font
					(size 1.27 1.27)
				)
			)
		)
		(duplicate_pad_numbers_are_jumpers no)
		(fp_line
			(start 0.7874 -0.4064)
			(end 0.7874 0.4064)
			(stroke
				(width 0.1524)
				(type default)
			)
			(layer "F.SilkS")
		)
		(fp_line
			(start -0.7874 -0.4064)
			(end 0.7874 -0.4064)
			(stroke
				(width 0.1524)
				(type default)
			)
			(layer "F.SilkS")
		)
		(fp_line
			(start 0.7874 0.4064)
			(end -0.7874 0.4064)
			(stroke
				(width 0.1524)
				(type default)
			)
			(layer "F.SilkS")
		)
		(fp_line
			(start -0.7874 0.4064)
			(end -0.7874 -0.4064)
			(stroke
				(width 0.1524)
				(type default)
			)
			(layer "F.SilkS")
		)
		(fp_poly
			(pts
				(xy -0.508 0.2794) (xy -0.508 0.2286) (xy -0.635 0.2286) (xy -0.635 -0.254) (xy -0.5334 -0.254)
				(xy -0.5334 -0.2794) (xy 0.5334 -0.2794) (xy 0.5334 -0.254) (xy 0.635 -0.254) (xy 0.635 0.254) (xy 0.5334 0.254)
				(xy 0.5334 0.2794)
			)
			(stroke
				(width 0)
				(type default)
			)
			(fill no)
			(layer "F.CrtYd")
		)
		(pad "1" smd rect
			(at 0.40005 0 90)
			(size 0.4572 0.508)
			(layers "F.Cu" "F.Mask" "F.Paste")
			(net "UART_T4_NODE1_TXD")
		)
		(pad "2" smd rect
			(at -0.40005 0 90)
			(size 0.4572 0.508)
			(layers "F.Cu" "F.Mask" "F.Paste")
			(net "UART_T4_NODE1_TXD_R")
		)
	)
	(footprint ""
		(layer "F.Cu")
		(at 38.681152 -4.500372)
		(property "Reference" "C853"
			(at -14.711172 1.896364 0)
			(unlocked yes)
			(layer "F.SilkS")
			(effects
				(font
					(size 0.7874 0.5842)
					(thickness 0.1524)
				)
				(justify left)
			)
		)
		(property "Value" ""
			(at 0 0 0)
			(layer "F.Fab")
			(effects
				(font
					(size 1.27 1.27)
				)
			)
		)
		(duplicate_pad_numbers_are_jumpers no)
		(fp_line
			(start -0.7874 -0.4064)
			(end 0.7874 -0.4064)
			(stroke
				(width 0.1524)
				(type default)
			)
			(layer "F.SilkS")
		)
		(fp_line
			(start -0.7874 0.4064)
			(end -0.7874 -0.4064)
			(stroke
				(width 0.1524)
				(type default)
			)
			(layer "F.SilkS")
		)
		(fp_line
			(start 0 0.381)
			(end 0 -0.381)
			(stroke
				(width 0.1524)
				(type default)
			)
			(layer "F.SilkS")
		)
		(fp_line
			(start 0.7874 -0.4064)
			(end 0.7874 0.4064)
			(stroke
				(width 0.1524)
				(type default)
			)
			(layer "F.SilkS")
		)
		(fp_line
			(start 0.7874 0.4064)
			(end -0.7874 0.4064)
			(stroke
				(width 0.1524)
				(type default)
			)
			(layer "F.SilkS")
		)
		(fp_poly
			(pts
				(xy -0.5334 0.254) (xy -0.635 0.254) (xy -0.635 0.2286) (xy -0.635 -0.254) (xy -0.5334 -0.254) (xy -0.5334 -0.2794)
				(xy 0.5334 -0.2794) (xy 0.5334 -0.254) (xy 0.635 -0.254) (xy 0.635 0.254) (xy 0.5334 0.254) (xy 0.5334 0.2794)
				(xy -0.508 0.2794) (xy -0.5334 0.2794)
			)
			(stroke
				(width 0)
				(type default)
			)
			(fill no)
			(layer "F.CrtYd")
		)
		(pad "1" smd rect
			(at 0.40005 0)
			(size 0.4572 0.508)
			(layers "F.Cu" "F.Mask" "F.Paste")
			(net "GND")
		)
		(pad "2" smd rect
			(at -0.40005 0)
			(size 0.4572 0.508)
			(layers "F.Cu" "F.Mask" "F.Paste")
			(net "P3V3_STB_NODE1")
		)
	)
	(footprint ""
		(layer "F.Cu")
		(at 95.113094 -140.101066 180)
		(property "Reference" "C815"
			(at 1.865122 4.19989 0)
			(unlocked yes)
			(layer "F.SilkS")
			(effects
				(font
					(size 0.7874 0.5842)
					(thickness 0.1524)
				)
				(justify left)
			)
		)
		(property "Value" ""
			(at 0 0 180)
			(layer "F.Fab")
			(effects
				(font
					(size 1.27 1.27)
				)
			)
		)
		(duplicate_pad_numbers_are_jumpers no)
		(fp_line
			(start 0.7874 0.4064)
			(end -0.7874 0.4064)
			(stroke
				(width 0.1524)
				(type default)
			)
			(layer "F.SilkS")
		)
		(fp_line
			(start 0.7874 -0.4064)
			(end 0.7874 0.4064)
			(stroke
				(width 0.1524)
				(type default)
			)
			(layer "F.SilkS")
		)
		(fp_line
			(start 0 0.381)
			(end 0 -0.381)
			(stroke
				(width 0.1524)
				(type default)
			)
			(layer "F.SilkS")
		)
		(fp_line
			(start -0.7874 0.4064)
			(end -0.7874 -0.4064)
			(stroke
				(width 0.1524)
				(type default)
			)
			(layer "F.SilkS")
		)
		(fp_line
			(start -0.7874 -0.4064)
			(end 0.7874 -0.4064)
			(stroke
				(width 0.1524)
				(type default)
			)
			(layer "F.SilkS")
		)
		(fp_poly
			(pts
				(xy -0.5334 0.254) (xy -0.635 0.254) (xy -0.635 0.2286) (xy -0.635 -0.254) (xy -0.5334 -0.254) (xy -0.5334 -0.2794)
				(xy 0.5334 -0.2794) (xy 0.5334 -0.254) (xy 0.635 -0.254) (xy 0.635 0.254) (xy 0.5334 0.254) (xy 0.5334 0.2794)
				(xy -0.508 0.2794) (xy -0.5334 0.2794)
			)
			(stroke
				(width 0)
				(type default)
			)
			(fill no)
			(layer "F.CrtYd")
		)
		(pad "1" smd rect
			(at 0.40005 0 180)
			(size 0.4572 0.508)
			(layers "F.Cu" "F.Mask" "F.Paste")
			(net "P1V05_SUS_NODE1_ADJ")
		)
		(pad "2" smd rect
			(at -0.40005 0 180)
			(size 0.4572 0.508)
			(layers "F.Cu" "F.Mask" "F.Paste")
			(net "P1V05_SUS_NODE1_ADJ_S")
		)
	)
	(footprint ""
		(layer "F.Cu")
		(at 70.639686 -148.476462 90)
		(property "Reference" "R304"
			(at 1.233932 -0.125984 90)
			(unlocked yes)
			(layer "F.SilkS")
			(effects
				(font
					(size 0.7874 0.5842)
					(thickness 0.1524)
				)
				(justify left)
			)
		)
		(property "Value" ""
			(at 0 0 90)
			(layer "F.Fab")
			(effects
				(font
					(size 1.27 1.27)
				)
			)
		)
		(duplicate_pad_numbers_are_jumpers no)
		(fp_line
			(start 0.7874 -0.4064)
			(end 0.7874 0.4064)
			(stroke
				(width 0.1524)
				(type default)
			)
			(layer "F.SilkS")
		)
		(fp_line
			(start -0.7874 -0.4064)
			(end 0.7874 -0.4064)
			(stroke
				(width 0.1524)
				(type default)
			)
			(layer "F.SilkS")
		)
		(fp_line
			(start 0.7874 0.4064)
			(end -0.7874 0.4064)
			(stroke
				(width 0.1524)
				(type default)
			)
			(layer "F.SilkS")
		)
		(fp_line
			(start -0.7874 0.4064)
			(end -0.7874 -0.4064)
			(stroke
				(width 0.1524)
				(type default)
			)
			(layer "F.SilkS")
		)
		(fp_poly
			(pts
				(xy -0.508 0.2794) (xy -0.508 0.2286) (xy -0.635 0.2286) (xy -0.635 -0.254) (xy -0.5334 -0.254)
				(xy -0.5334 -0.2794) (xy 0.5334 -0.2794) (xy 0.5334 -0.254) (xy 0.635 -0.254) (xy 0.635 0.254) (xy 0.5334 0.254)
				(xy 0.5334 0.2794)
			)
			(stroke
				(width 0)
				(type default)
			)
			(fill no)
			(layer "F.CrtYd")
		)
		(pad "1" smd rect
			(at 0.40005 0 90)
			(size 0.4572 0.508)
			(layers "F.Cu" "F.Mask" "F.Paste")
			(net "P3V3_NODE1")
		)
		(pad "2" smd rect
			(at -0.40005 0 90)
			(size 0.4572 0.508)
			(layers "F.Cu" "F.Mask" "F.Paste")
			(net "BMC_NODE1_JTAG_TCK")
		)
	)
	(footprint ""
		(layer "F.Cu")
		(at 148.19376 -188.126624 90)
		(property "Reference" "C753"
			(at 5.519674 -2.554732 90)
			(unlocked yes)
			(layer "F.SilkS")
			(effects
				(font
					(size 0.7874 0.5842)
					(thickness 0.1524)
				)
				(justify left)
			)
		)
		(property "Value" ""
			(at 0 0 90)
			(layer "F.Fab")
			(effects
				(font
					(size 1.27 1.27)
				)
			)
		)
		(duplicate_pad_numbers_are_jumpers no)
		(fp_line
			(start 0.7874 -0.4064)
			(end 0.7874 0.4064)
			(stroke
				(width 0.1524)
				(type default)
			)
			(layer "F.SilkS")
		)
		(fp_line
			(start -0.7874 -0.4064)
			(end 0.7874 -0.4064)
			(stroke
				(width 0.1524)
				(type default)
			)
			(layer "F.SilkS")
		)
		(fp_line
			(start 0 0.381)
			(end 0 -0.381)
			(stroke
				(width 0.1524)
				(type default)
			)
			(layer "F.SilkS")
		)
		(fp_line
			(start 0.7874 0.4064)
			(end -0.7874 0.4064)
			(stroke
				(width 0.1524)
				(type default)
			)
			(layer "F.SilkS")
		)
		(fp_line
			(start -0.7874 0.4064)
			(end -0.7874 -0.4064)
			(stroke
				(width 0.1524)
				(type default)
			)
			(layer "F.SilkS")
		)
		(fp_poly
			(pts
				(xy -0.5334 0.254) (xy -0.635 0.254) (xy -0.635 0.2286) (xy -0.635 -0.254) (xy -0.5334 -0.254) (xy -0.5334 -0.2794)
				(xy 0.5334 -0.2794) (xy 0.5334 -0.254) (xy 0.635 -0.254) (xy 0.635 0.254) (xy 0.5334 0.254) (xy 0.5334 0.2794)
				(xy -0.508 0.2794) (xy -0.5334 0.2794)
			)
			(stroke
				(width 0)
				(type default)
			)
			(fill no)
			(layer "F.CrtYd")
		)
		(pad "1" smd rect
			(at 0.40005 0 90)
			(size 0.4572 0.508)
			(layers "F.Cu" "F.Mask" "F.Paste")
			(net "UART_T12_NODE2_TXD_R")
		)
		(pad "2" smd rect
			(at -0.40005 0 90)
			(size 0.4572 0.508)
			(layers "F.Cu" "F.Mask" "F.Paste")
			(net "GND")
		)
	)
	(footprint ""
		(layer "F.Cu")
		(at 32.3596 -132.81533 90)
		(property "Reference" "J22"
			(at 0.906018 0.44958 0)
			(unlocked yes)
			(layer "F.SilkS")
			(effects
				(font
					(size 0.7874 0.5842)
					(thickness 0.1524)
				)
				(justify left)
			)
		)
		(property "Value" ""
			(at 0 0 90)
			(layer "F.Fab")
			(effects
				(font
					(size 1.27 1.27)
				)
			)
		)
		(duplicate_pad_numbers_are_jumpers no)
		(fp_poly
			(pts
				(xy 0.2794 0.907796) (xy 0.254 0.907796) (xy 0.254 1.0414) (xy -0.254 1.0414) (xy -0.254 1.034796)
				(xy -0.254 0.933196) (xy -0.2794 0.933196) (xy -0.2794 -0.133604) (xy -0.254 -0.133604) (xy -0.254 -0.235204)
				(xy 0.254 -0.235204) (xy 0.254 -0.133604) (xy 0.2794 -0.133604)
			)
			(stroke
				(width 0)
				(type default)
			)
			(fill no)
			(layer "F.CrtYd")
		)
		(pad "1" smd custom
			(at 0 -0.000254 90)
			(size 0.127 0.127)
			(layers "F.Cu" "F.Mask" "F.Paste")
			(net "P1V538_STB_NODE1_ADJ_S")
			(options
				(clearance outline)
				(anchor circle)
			)
			(primitives
				(gr_poly
					(pts
						(xy -0.127 0.508) (xy -0.127 -0.0508) (xy -0.254 -0.0508) (xy -0.254 -0.508) (xy 0.254 -0.508)
						(xy 0.254 -0.0508) (xy 0.127 -0.0508) (xy 0.127 0.508)
					)
					(width 0)
					(fill yes)
				)
			)
		)
		(pad "2" smd rect
			(at 0 0.799846 180)
			(size 0.4572 0.508)
			(layers "F.Cu" "F.Mask" "F.Paste")
			(net "P1V538_BMC_NODE1")
		)
		(zone
			(layer "F.Cu")
			(hatch none 0.5)
			(connect_pads
				(clearance 0)
			)
			(min_thickness 0.25)
			(keepout
				(tracks allowed)
				(vias not_allowed)
				(pads allowed)
				(copperpour not_allowed)
				(footprints allowed)
			)
			(placement
				(enabled no)
				(sheetname "")
			)
			(fill
				(thermal_gap 0.5)
				(thermal_bridge_width 0.5)
				(island_removal_mode 0)
			)
			(polygon
				(pts
					(xy 33.445196 -132.51053) (xy 33.445196 -133.12013) (xy 32.073596 -133.12013) (xy 32.073596 -132.51053)
				)
			)
		)
	)
)
